(kicad_pcb
	(version 20241229)
	(generator "pcbnew")
	(generator_version "9.0")
	(general
		(thickness 1.294)
		(legacy_teardrops no)
	)
	(paper "A3")
	(title_block
		(title "Kintex 410T devboard")
		(date "2024-04-03")
		(rev "1.1.2")
		(comment 9 "footprints 239-242 of 975")
	)
	(layers
		(0 "F.Cu" mixed)
		(4 "In1.Cu" power)
		(6 "In2.Cu" power)
		(8 "In3.Cu" mixed)
		(10 "In4.Cu" power)
		(12 "In5.Cu" mixed)
		(14 "In6.Cu" power)
		(16 "In7.Cu" mixed)
		(18 "In8.Cu" power)
		(2 "B.Cu" mixed)
		(9 "F.Adhes" user "F.Adhesive")
		(11 "B.Adhes" user "B.Adhesive")
		(13 "F.Paste" user)
		(15 "B.Paste" user)
		(5 "F.SilkS" user "F.Silkscreen")
		(7 "B.SilkS" user "B.Silkscreen")
		(1 "F.Mask" user)
		(3 "B.Mask" user)
		(17 "Dwgs.User" user "User.Drawings")
		(19 "Cmts.User" user "User.Comments")
		(21 "Eco1.User" user "User.Eco1")
		(23 "Eco2.User" user "User.Eco2")
		(25 "Edge.Cuts" user)
		(27 "Margin" user)
		(31 "F.CrtYd" user "F.Courtyard")
		(29 "B.CrtYd" user "B.Courtyard")
		(35 "F.Fab" user)
		(33 "B.Fab" user)
	)
	(footprint "antmicro-footprints:SW_DIP_SPSTx03_Slide_Copal_CVS-03xB_W5.9mm_P1mm"
		(layer "F.Cu")
		(at 203.101 74.033 90)
		(descr "SMD 3x-dip-switch SPST Copal_CVS-03xB, Slide, row spacing 5.9 mm (232 mils), body size  (see http://www.nidec-copal-electronics.com/e/catalog/switch/cvs.pdf)")
		(tags "SMD DIP Switch SPST Slide")
		(property "Reference" "SW1"
			(at -1.267 -3.001 90)
			(layer "F.SilkS")
			(effects
				(font
					(size 0.7 0.7)
					(thickness 0.15)
				)
				(justify left bottom)
			)
		)
		(property "Value" "CVS-03B"
			(at 0.248 4.799 90)
			(layer "F.Fab")
			(effects
				(font
					(size 0.7 0.7)
					(thickness 0.15)
				)
				(justify left bottom)
			)
		)
		(property "Description" "Slide switch"
			(at 0 0 90)
			(layer "F.Fab")
			(hide yes)
			(effects
				(font
					(size 1.27 1.27)
					(thickness 0.15)
				)
			)
		)
		(property "Author" "Antmicro"
			(at 277.134 -129.068 0)
			(layer "F.Fab")
			(hide yes)
			(effects
				(font
					(size 1 1)
					(thickness 0.15)
				)
			)
		)
		(property "License" "Apache-2.0"
			(at 277.134 -129.068 0)
			(layer "F.Fab")
			(hide yes)
			(effects
				(font
					(size 1 1)
					(thickness 0.15)
				)
			)
		)
		(property "MPN" "CVS-03B"
			(at 277.134 -129.068 0)
			(layer "F.Fab")
			(hide yes)
			(effects
				(font
					(size 1 1)
					(thickness 0.15)
				)
			)
		)
		(property "Manufacturer" "Nidec Components"
			(at 277.134 -129.068 0)
			(layer "F.Fab")
			(hide yes)
			(effects
				(font
					(size 1 1)
					(thickness 0.15)
				)
			)
		)
		(sheetname "FPGA Config")
		(sheetfile "fpga-config.kicad_sch")
		(attr smd)
		(fp_line
			(start -1.51 -2.411)
			(end 1.61 -2.411)
			(stroke
				(width 0.15)
				(type solid)
			)
			(layer "F.SilkS")
		)
		(fp_line
			(start -1.51 2.41)
			(end 1.61 2.41)
			(stroke
				(width 0.15)
				(type solid)
			)
			(layer "F.SilkS")
		)
		(fp_circle
			(center -3.33 -1.641)
			(end -3.281 -1.641)
			(stroke
				(width 0.15)
				(type solid)
			)
			(fill yes)
			(layer "F.SilkS")
		)
		(fp_rect
			(start -3.56 -2.5)
			(end 3.66 2.49)
			(stroke
				(width 0.05)
				(type solid)
			)
			(fill no)
			(layer "F.CrtYd")
		)
		(fp_line
			(start 2.398 -2)
			(end 2.398 1.999)
			(stroke
				(width 0.15)
				(type solid)
			)
			(layer "F.Fab")
		)
		(fp_line
			(start -1.301 -2)
			(end 2.398 -2)
			(stroke
				(width 0.15)
				(type solid)
			)
			(layer "F.Fab")
		)
		(fp_line
			(start 1.05 -1.25)
			(end -0.951 -1.25)
			(stroke
				(width 0.15)
				(type solid)
			)
			(layer "F.Fab")
		)
		(fp_line
			(start -0.285 -1.25)
			(end -0.285 -0.75)
			(stroke
				(width 0.15)
				(type solid)
			)
			(layer "F.Fab")
		)
		(fp_line
			(start -0.951 -1.25)
			(end -0.951 -0.75)
			(stroke
				(width 0.15)
				(type solid)
			)
			(layer "F.Fab")
		)
		(fp_line
			(start -0.951 -1.151)
			(end -0.285 -1.151)
			(stroke
				(width 0.15)
				(type solid)
			)
			(layer "F.Fab")
		)
		(fp_line
			(start -0.951 -1.051)
			(end -0.285 -1.051)
			(stroke
				(width 0.15)
				(type solid)
			)
			(layer "F.Fab")
		)
		(fp_line
			(start -2.301 -1)
			(end -1.301 -2)
			(stroke
				(width 0.15)
				(type solid)
			)
			(layer "F.Fab")
		)
		(fp_line
			(start -0.951 -0.952)
			(end -0.285 -0.952)
			(stroke
				(width 0.15)
				(type solid)
			)
			(layer "F.Fab")
		)
		(fp_line
			(start -0.951 -0.85)
			(end -0.285 -0.85)
			(stroke
				(width 0.15)
				(type solid)
			)
			(layer "F.Fab")
		)
		(fp_line
			(start 1.05 -0.75)
			(end 1.05 -1.25)
			(stroke
				(width 0.15)
				(type solid)
			)
			(layer "F.Fab")
		)
		(fp_line
			(start -0.951 -0.75)
			(end 1.05 -0.75)
			(stroke
				(width 0.15)
				(type solid)
			)
			(layer "F.Fab")
		)
		(fp_line
			(start 1.05 -0.25)
			(end -0.951 -0.25)
			(stroke
				(width 0.15)
				(type solid)
			)
			(layer "F.Fab")
		)
		(fp_line
			(start -0.285 -0.25)
			(end -0.285 0.247)
			(stroke
				(width 0.15)
				(type solid)
			)
			(layer "F.Fab")
		)
		(fp_line
			(start -0.951 -0.25)
			(end -0.951 0.247)
			(stroke
				(width 0.15)
				(type solid)
			)
			(layer "F.Fab")
		)
		(fp_line
			(start -0.951 -0.15)
			(end -0.285 -0.15)
			(stroke
				(width 0.15)
				(type solid)
			)
			(layer "F.Fab")
		)
		(fp_line
			(start -0.951 -0.053)
			(end -0.285 -0.053)
			(stroke
				(width 0.15)
				(type solid)
			)
			(layer "F.Fab")
		)
		(fp_line
			(start -0.951 0.05)
			(end -0.285 0.05)
			(stroke
				(width 0.15)
				(type solid)
			)
			(layer "F.Fab")
		)
		(fp_line
			(start -0.951 0.147)
			(end -0.285 0.147)
			(stroke
				(width 0.15)
				(type solid)
			)
			(layer "F.Fab")
		)
		(fp_line
			(start 1.05 0.247)
			(end 1.05 -0.25)
			(stroke
				(width 0.15)
				(type solid)
			)
			(layer "F.Fab")
		)
		(fp_line
			(start -0.951 0.247)
			(end 1.05 0.247)
			(stroke
				(width 0.15)
				(type solid)
			)
			(layer "F.Fab")
		)
		(fp_line
			(start 1.05 0.747)
			(end -0.951 0.747)
			(stroke
				(width 0.15)
				(type solid)
			)
			(layer "F.Fab")
		)
		(fp_line
			(start -0.285 0.747)
			(end -0.285 1.249)
			(stroke
				(width 0.15)
				(type solid)
			)
			(layer "F.Fab")
		)
		(fp_line
			(start -0.951 0.747)
			(end -0.951 1.249)
			(stroke
				(width 0.15)
				(type solid)
			)
			(layer "F.Fab")
		)
		(fp_line
			(start -0.951 0.847)
			(end -0.285 0.847)
			(stroke
				(width 0.15)
				(type solid)
			)
			(layer "F.Fab")
		)
		(fp_line
			(start -0.951 0.949)
			(end -0.285 0.949)
			(stroke
				(width 0.15)
				(type solid)
			)
			(layer "F.Fab")
		)
		(fp_line
			(start -0.951 1.05)
			(end -0.285 1.05)
			(stroke
				(width 0.15)
				(type solid)
			)
			(layer "F.Fab")
		)
		(fp_line
			(start -0.951 1.148)
			(end -0.285 1.148)
			(stroke
				(width 0.15)
				(type solid)
			)
			(layer "F.Fab")
		)
		(fp_line
			(start 1.05 1.249)
			(end 1.05 0.747)
			(stroke
				(width 0.15)
				(type solid)
			)
			(layer "F.Fab")
		)
		(fp_line
			(start -0.951 1.249)
			(end 1.05 1.249)
			(stroke
				(width 0.15)
				(type solid)
			)
			(layer "F.Fab")
		)
		(fp_line
			(start 2.398 1.999)
			(end -2.301 1.999)
			(stroke
				(width 0.15)
				(type solid)
			)
			(layer "F.Fab")
		)
		(fp_line
			(start -2.301 1.999)
			(end -2.301 -1)
			(stroke
				(width 0.15)
				(type solid)
			)
			(layer "F.Fab")
		)
		(pad "1" smd rect
			(at -2.899 -1 90)
			(size 1.2 0.5)
			(layers "F.Cu" "F.Mask" "F.Paste")
			(net 300 "/FPGA Config/MODE0")
			(pinfunction "1")
			(pintype "passive")
		)
		(pad "2" smd rect
			(at -2.899 0 90)
			(size 1.2 0.5)
			(layers "F.Cu" "F.Mask" "F.Paste")
			(net 299 "/FPGA Config/MODE1")
			(pinfunction "2")
			(pintype "passive")
		)
		(pad "3" smd rect
			(at -2.899 0.997 90)
			(size 1.2 0.5)
			(layers "F.Cu" "F.Mask" "F.Paste")
			(net 298 "/FPGA Config/MODE2")
			(pinfunction "3")
			(pintype "passive")
		)
		(pad "4" smd rect
			(at 2.999 0.997 90)
			(size 1.2 0.5)
			(layers "F.Cu" "F.Mask" "F.Paste")
			(net 1 "GND")
			(pinfunction "4")
			(pintype "passive")
		)
		(pad "5" smd rect
			(at 2.999 0 90)
			(size 1.2 0.5)
			(layers "F.Cu" "F.Mask" "F.Paste")
			(net 1 "GND")
			(pinfunction "5")
			(pintype "passive")
		)
		(pad "6" smd rect
			(at 2.999 -1 90)
			(size 1.2 0.5)
			(layers "F.Cu" "F.Mask" "F.Paste")
			(net 1 "GND")
			(pinfunction "6")
			(pintype "passive")
		)
		(pad "7" smd rect
			(at -2.101 -2 90)
			(size 0.7 0.7)
			(layers "F.Cu" "F.Mask" "F.Paste")
			(net 1 "GND")
			(pinfunction "7")
			(pintype "power_in")
		)
		(pad "7" smd rect
			(at -2.101 1.999 90)
			(size 0.7 0.7)
			(layers "F.Cu" "F.Mask" "F.Paste")
			(net 1 "GND")
			(pinfunction "7")
			(pintype "power_in")
		)
		(pad "7" smd rect
			(at 2.201 -2 90)
			(size 0.7 0.7)
			(layers "F.Cu" "F.Mask" "F.Paste")
			(net 1 "GND")
			(pinfunction "7")
			(pintype "power_in")
		)
		(pad "7" smd rect
			(at 2.201 1.999 90)
			(size 0.7 0.7)
			(layers "F.Cu" "F.Mask" "F.Paste")
			(net 1 "GND")
			(pinfunction "7")
			(pintype "power_in")
		)
	)
	(footprint "antmicro-footprints:R_0402_1005Metric"
		(layer "F.Cu")
		(at 210.9 165.4 90)
		(descr "Resistor SMD 0402")
		(tags "resistor SMD 0402")
		(property "Reference" "R69"
			(at -0.4 -5.25 90)
			(layer "F.SilkS")
			(effects
				(font
					(size 0.7 0.7)
					(thickness 0.15)
				)
				(justify left bottom)
			)
		)
		(property "Value" "R_10k_0402"
			(at 0 1.4 90)
			(layer "F.Fab")
			(effects
				(font
					(size 0.7 0.7)
					(thickness 0.15)
				)
				(justify left bottom)
			)
		)
		(property "Description" "SMD Chip Resistor, 10 kohm, ± 1%, 62.5 mW, 0402 [1005 Metric], Thick Film, General Purpose"
			(at 0 0 90)
			(layer "F.Fab")
			(hide yes)
			(effects
				(font
					(size 1.27 1.27)
					(thickness 0.15)
				)
			)
		)
		(property "Author" "Antmicro"
			(at 376.3 -45.5 0)
			(layer "F.Fab")
			(hide yes)
			(effects
				(font
					(size 1 1)
					(thickness 0.15)
				)
			)
		)
		(property "License" "Apache-2.0"
			(at 376.3 -45.5 0)
			(layer "F.Fab")
			(hide yes)
			(effects
				(font
					(size 1 1)
					(thickness 0.15)
				)
			)
		)
		(property "MPN" "CR0402-FX-1002GLF"
			(at 376.3 -45.5 0)
			(layer "F.Fab")
			(hide yes)
			(effects
				(font
					(size 1 1)
					(thickness 0.15)
				)
			)
		)
		(property "Manufacturer" "Bourns"
			(at 376.3 -45.5 0)
			(layer "F.Fab")
			(hide yes)
			(effects
				(font
					(size 1 1)
					(thickness 0.15)
				)
			)
		)
		(property "Tolerance" "1%"
			(at 376.3 -45.5 0)
			(layer "F.Fab")
			(hide yes)
			(effects
				(font
					(size 1 1)
					(thickness 0.15)
				)
			)
		)
		(property "Val" "10k"
			(at 376.3 -45.5 0)
			(layer "F.Fab")
			(hide yes)
			(effects
				(font
					(size 1 1)
					(thickness 0.15)
				)
			)
		)
		(sheetname "SPI Flash + SD Card")
		(sheetfile "spi-flash.kicad_sch")
		(attr smd)
		(fp_rect
			(start -0.925 -0.47)
			(end 0.925 0.47)
			(stroke
				(width 0.05)
				(type default)
			)
			(fill no)
			(layer "F.CrtYd")
		)
		(fp_rect
			(start -0.5 -0.25)
			(end 0.5 0.25)
			(stroke
				(width 0.15)
				(type solid)
			)
			(fill no)
			(layer "F.Fab")
		)
		(pad "1" smd roundrect
			(at -0.48 0 90)
			(size 0.59 0.64)
			(layers "F.Cu" "F.Mask" "F.Paste")
			(roundrect_rratio 0.25)
			(net 407 "/FPGA Bank 33 & 34/USR_FLASH_0.~{CS}")
			(pintype "passive")
		)
		(pad "2" smd roundrect
			(at 0.48 0 90)
			(size 0.59 0.64)
			(layers "F.Cu" "F.Mask" "F.Paste")
			(roundrect_rratio 0.25)
			(net 26 "+1V8")
			(pintype "passive")
		)
	)
	(footprint "antmicro-footprints:C_0603_1608Metric"
		(layer "F.Cu")
		(at 261.95 149.85 90)
		(descr "Capacitor SMD 0603")
		(tags "capacitor 0603")
		(property "Reference" "C222"
			(at -1.55 -0.75 90)
			(layer "F.SilkS")
			(effects
				(font
					(size 0.7 0.7)
					(thickness 0.15)
				)
				(justify left bottom)
			)
		)
		(property "Value" "C_10u_25V_0603"
			(at 0 1.6 90)
			(layer "F.Fab")
			(effects
				(font
					(size 0.7 0.7)
					(thickness 0.15)
				)
				(justify left bottom)
			)
		)
		(property "Description" "SMD Multilayer Ceramic Capacitor, 10 µF, 25 V, 0603 [1608 Metric], ± 20%, X5R, C"
			(at 0 0 90)
			(layer "F.Fab")
			(hide yes)
			(effects
				(font
					(size 1.27 1.27)
					(thickness 0.15)
				)
			)
		)
		(property "Author" "Antmicro"
			(at 411.8 -112.1 0)
			(layer "F.Fab")
			(hide yes)
			(effects
				(font
					(size 1 1)
					(thickness 0.15)
				)
			)
		)
		(property "Dielectric" ""
			(at 411.8 -112.1 0)
			(layer "F.Fab")
			(hide yes)
			(effects
				(font
					(size 1 1)
					(thickness 0.15)
				)
			)
		)
		(property "License" "Apache-2.0"
			(at 411.8 -112.1 0)
			(layer "F.Fab")
			(hide yes)
			(effects
				(font
					(size 1 1)
					(thickness 0.15)
				)
			)
		)
		(property "MPN" "C1608X5R1E106M080AC"
			(at 411.8 -112.1 0)
			(layer "F.Fab")
			(hide yes)
			(effects
				(font
					(size 1 1)
					(thickness 0.15)
				)
			)
		)
		(property "Manufacturer" "TDK"
			(at 411.8 -112.1 0)
			(layer "F.Fab")
			(hide yes)
			(effects
				(font
					(size 1 1)
					(thickness 0.15)
				)
			)
		)
		(property "Val" "10u"
			(at 411.8 -112.1 0)
			(layer "F.Fab")
			(hide yes)
			(effects
				(font
					(size 1 1)
					(thickness 0.15)
				)
			)
		)
		(property "Voltage" "25V"
			(at 411.8 -112.1 0)
			(layer "F.Fab")
			(hide yes)
			(effects
				(font
					(size 1 1)
					(thickness 0.15)
				)
			)
		)
		(sheetname "USB PHY")
		(sheetfile "usb-phy.kicad_sch")
		(attr smd)
		(fp_line
			(start -0.15 -0.4)
			(end 0.15 -0.4)
			(stroke
				(width 0.15)
				(type solid)
			)
			(layer "F.SilkS")
		)
		(fp_line
			(start -0.15 0.4)
			(end 0.15 0.4)
			(stroke
				(width 0.15)
				(type solid)
			)
			(layer "F.SilkS")
		)
		(fp_rect
			(start -1.25 -0.65)
			(end 1.25 0.65)
			(stroke
				(width 0.05)
				(type solid)
			)
			(fill no)
			(layer "F.CrtYd")
		)
		(fp_rect
			(start -0.8 -0.4)
			(end 0.8 0.4)
			(stroke
				(width 0.15)
				(type solid)
			)
			(fill no)
			(layer "F.Fab")
		)
		(pad "1" smd roundrect
			(at -0.7 0 90)
			(size 0.8 1)
			(layers "F.Cu" "F.Mask" "F.Paste")
			(roundrect_rratio 0.2)
			(net 1 "GND")
			(pintype "passive")
		)
		(pad "2" smd roundrect
			(at 0.7 0 90)
			(size 0.8 1)
			(layers "F.Cu" "F.Mask" "F.Paste")
			(roundrect_rratio 0.2)
			(net 704 "/Power supply/USB_DBG_PD.VBUS")
			(pintype "passive")
		)
	)
	(footprint "antmicro-footprints:R_0603_1608Metric"
		(layer "F.Cu")
		(at 161.6 153.3)
		(descr "Resistor SMD 0603")
		(tags "resistor SMD 0603")
		(property "Reference" "R330"
			(at -1.15 1.4 0)
			(layer "F.SilkS")
			(effects
				(font
					(size 0.7 0.7)
					(thickness 0.15)
				)
				(justify left bottom)
			)
		)
		(property "Value" "R_0R_22.4A_0603"
			(at 0 1.6 0)
			(layer "F.Fab")
			(effects
				(font
					(size 0.7 0.7)
					(thickness 0.15)
				)
				(justify left bottom)
			)
		)
		(property "Description" "SMD Chip Resistor"
			(at 0 0 0)
			(layer "F.Fab")
			(hide yes)
			(effects
				(font
					(size 1.27 1.27)
					(thickness 0.15)
				)
			)
		)
		(property "Author" "Antmicro"
			(at 0 0 0)
			(layer "F.Fab")
			(hide yes)
			(effects
				(font
					(size 1 1)
					(thickness 0.15)
				)
			)
		)
		(property "License" "Apache-2.0"
			(at 0 0 0)
			(layer "F.Fab")
			(hide yes)
			(effects
				(font
					(size 1 1)
					(thickness 0.15)
				)
			)
		)
		(property "MPN" "PMR03EZPJ000"
			(at 0 0 0)
			(layer "F.Fab")
			(hide yes)
			(effects
				(font
					(size 1 1)
					(thickness 0.15)
				)
			)
		)
		(property "Manufacturer" "ROHM Semiconductor"
			(at 0 0 0)
			(layer "F.Fab")
			(hide yes)
			(effects
				(font
					(size 1 1)
					(thickness 0.15)
				)
			)
		)
		(property "Max. Curr." "22.4A"
			(at 0 0 0)
			(layer "F.Fab")
			(hide yes)
			(effects
				(font
					(size 1 1)
					(thickness 0.15)
				)
			)
		)
		(property "Tolerance" "template_tolerance"
			(at 0 0 0)
			(layer "F.Fab")
			(hide yes)
			(effects
				(font
					(size 1 1)
					(thickness 0.15)
				)
			)
		)
		(property "Val" "0R"
			(at 0 0 0)
			(layer "F.Fab")
			(hide yes)
			(effects
				(font
					(size 1 1)
					(thickness 0.15)
				)
			)
		)
		(sheetname "DC-DC Converters")
		(sheetfile "dc-dc.kicad_sch")
		(attr smd)
		(fp_line
			(start -0.15 -0.4)
			(end 0.15 -0.4)
			(stroke
				(width 0.15)
				(type solid)
			)
			(layer "F.SilkS")
		)
		(fp_line
			(start -0.15 0.4)
			(end 0.15 0.4)
			(stroke
				(width 0.15)
				(type solid)
			)
			(layer "F.SilkS")
		)
		(fp_rect
			(start -1.25 -0.65)
			(end 1.25 0.65)
			(stroke
				(width 0.05)
				(type solid)
			)
			(fill no)
			(layer "F.CrtYd")
		)
		(fp_rect
			(start -0.8 -0.4)
			(end 0.8 0.4)
			(stroke
				(width 0.15)
				(type solid)
			)
			(fill no)
			(layer "F.Fab")
		)
		(pad "1" smd roundrect
			(at -0.7 0)
			(size 0.8 1)
			(layers "F.Cu" "F.Mask" "F.Paste")
			(roundrect_rratio 0.2)
			(net 750 "/DC-DC Converters/VDDR_VTT")
			(pintype "passive")
		)
		(pad "2" smd roundrect
			(at 0.7 0)
			(size 0.8 1)
			(layers "F.Cu" "F.Mask" "F.Paste")
			(roundrect_rratio 0.2)
			(net 7 "+0V675_VTT")
			(pintype "passive")
		)
	)
)
